# S9S_MB_2U (Grand Teton) — schematic netlist excerpt (pin names and nets, part order shuffled) for the footprints in the layout excerpt that follows; sources: Cadence DE-HDL packaged netlist, KiCad conversion of 03242023_DA0F0TMBIJ0_F0T_Motherboard_J_brd_V01_OCP.brd

R374  Q_RES  1K 1% EMPTY  pkg 0402LF  page 198 : A = P3V3_AUX ; B = FM_SPI_3V3_1V8_VOLTAGE
R2805  Q_RES  4.7K 5% EMPTY  pkg 0402LF  page 245 : A = P3V3_AUX ; B = SMB_FAN_3V3AUX_BUF_SCL
PC637  Q_CAP  22UF 16V 20% X6S  pkg C0805  page 279 : A = SW_P12V_PVCCINFAON_CPU0_FLT ; B = GND

(kicad_pcb
	(version 20260206)
	(generator "pcbnew")
	(generator_version "10.0")
	(general
		(thickness 1.6)
		(legacy_teardrops no)
	)
	(paper "A4")
	(title_block
		(title "03242023_DA0F0TMBIJ0_F0T_Motherboard_J_brd_V01_OCP.brd")
		(comment 1 "Grand Teton / footprints 5905-5907 of 6105")
	)
	(layers
		(0 "F.Cu" signal "TOP")
		(4 "In1.Cu" signal "GND")
		(6 "In2.Cu" signal "IN1")
		(8 "In3.Cu" signal "GND1")
		(10 "In4.Cu" signal "IN2")
		(12 "In5.Cu" signal "GND2")
		(14 "In6.Cu" signal "IN3")
		(16 "In7.Cu" signal "GND3")
		(18 "In8.Cu" signal "VCC")
		(20 "In9.Cu" signal "VCC1")
		(22 "In10.Cu" signal "GND4")
		(24 "In11.Cu" signal "IN4")
		(26 "In12.Cu" signal "GND5")
		(28 "In13.Cu" signal "IN5")
		(30 "In14.Cu" signal "GND6")
		(32 "In15.Cu" signal "IN6")
		(34 "In16.Cu" signal "GND7")
		(2 "B.Cu" signal "BOTTOM")
		(9 "F.Adhes" user "F.Adhesive")
		(11 "B.Adhes" user "B.Adhesive")
		(13 "F.Paste" user "Package Geometry/Pastemask Top")
		(15 "B.Paste" user "Package Geometry/Pastemask Bottom")
		(5 "F.SilkS" user "Ref Des/Silkscreen Top")
		(7 "B.SilkS" user "Ref Des/Silkscreen Bottom")
		(1 "F.Mask" user "Board Geometry/Soldermask Top")
		(3 "B.Mask" user "Board Geometry/Soldermask Bottom")
		(17 "Dwgs.User" user "User.Drawings")
		(19 "Cmts.User" user "User.Comments")
		(21 "Eco1.User" user "User.Eco1")
		(23 "Eco2.User" user "User.Eco2")
		(25 "Edge.Cuts" user "Board Geometry/Outline")
		(27 "Margin" user)
		(31 "F.CrtYd" user "Package Geometry/Place Bound Top")
		(29 "B.CrtYd" user "Package Geometry/Place Bound Bottom")
		(35 "F.Fab" user "Ref Des/Assembly Top")
		(33 "B.Fab" user "Ref Des/Assembly Bottom")
	)
	(footprint ""
		(layer "B.Cu")
		(at 416.02914 -158.92907)
		(property "Reference" "PC637"
			(at 0 0 0)
			(layer "B.SilkS")
			(hide yes)
			(effects
				(font
					(size 1.27 1.27)
				)
				(justify mirror)
			)
		)
		(property "Value" ""
			(at 0 0 0)
			(layer "B.Fab")
			(effects
				(font
					(size 1.27 1.27)
				)
				(justify mirror)
			)
		)
		(duplicate_pad_numbers_are_jumpers no)
		(fp_line
			(start -1.524 -0.762)
			(end -1.524 0.762)
			(stroke
				(width 0.1524)
				(type default)
			)
			(layer "B.SilkS")
		)
		(fp_line
			(start -1.524 0.762)
			(end 1.524 0.762)
			(stroke
				(width 0.1524)
				(type default)
			)
			(layer "B.SilkS")
		)
		(fp_line
			(start 1.524 -0.762)
			(end -1.524 -0.762)
			(stroke
				(width 0.1524)
				(type default)
			)
			(layer "B.SilkS")
		)
		(fp_line
			(start 1.524 0.762)
			(end 1.524 -0.762)
			(stroke
				(width 0.1524)
				(type default)
			)
			(layer "B.SilkS")
		)
		(fp_line
			(start -1.1049 -0.724916)
			(end 1.1049 -0.724916)
			(stroke
				(width 0.1)
				(type default)
			)
			(layer "B.Fab")
		)
		(fp_line
			(start -1.1049 0.724916)
			(end -1.1049 -0.724916)
			(stroke
				(width 0.1)
				(type default)
			)
			(layer "B.Fab")
		)
		(fp_line
			(start 1.1049 -0.724916)
			(end 1.1049 0.724916)
			(stroke
				(width 0.1)
				(type default)
			)
			(layer "B.Fab")
		)
		(fp_line
			(start 1.1049 0.724916)
			(end -1.1049 0.724916)
			(stroke
				(width 0.1)
				(type default)
			)
			(layer "B.Fab")
		)
		(pad "1" smd rect
			(at 0.889 0)
			(size 1.016 1.27)
			(layers "B.Cu" "B.Mask" "B.Paste")
			(net "SW_P12V_PVCCINFAON_CPU0_FLT")
		)
		(pad "2" smd rect
			(at -0.889 0)
			(size 1.016 1.27)
			(layers "B.Cu" "B.Mask" "B.Paste")
			(net "GND")
		)
	)
	(footprint ""
		(layer "B.Cu")
		(at 180.364384 -422.615868)
		(property "Reference" "R2805"
			(at 0 0 0)
			(layer "B.SilkS")
			(hide yes)
			(effects
				(font
					(size 1.27 1.27)
				)
				(justify mirror)
			)
		)
		(property "Value" ""
			(at 0 0 0)
			(layer "B.Fab")
			(effects
				(font
					(size 1.27 1.27)
				)
				(justify mirror)
			)
		)
		(duplicate_pad_numbers_are_jumpers no)
		(fp_line
			(start -0.7874 -0.4064)
			(end -0.7874 0.4064)
			(stroke
				(width 0.1524)
				(type default)
			)
			(layer "B.SilkS")
		)
		(fp_line
			(start -0.7874 0.4064)
			(end 0.7874 0.4064)
			(stroke
				(width 0.1524)
				(type default)
			)
			(layer "B.SilkS")
		)
		(fp_line
			(start 0.7874 -0.4064)
			(end -0.7874 -0.4064)
			(stroke
				(width 0.1524)
				(type default)
			)
			(layer "B.SilkS")
		)
		(fp_line
			(start 0.7874 0.4064)
			(end 0.7874 -0.4064)
			(stroke
				(width 0.1524)
				(type default)
			)
			(layer "B.SilkS")
		)
		(fp_line
			(start -0.67945 -0.3048)
			(end -0.67945 0.3048)
			(stroke
				(width 0.1)
				(type default)
			)
			(layer "B.Fab")
		)
		(fp_line
			(start -0.67945 0.3048)
			(end -0.120396 0.3048)
			(stroke
				(width 0.1)
				(type default)
			)
			(layer "B.Fab")
		)
		(fp_line
			(start -0.12065 -0.3048)
			(end -0.67945 -0.3048)
			(stroke
				(width 0.1)
				(type default)
			)
			(layer "B.Fab")
		)
		(fp_line
			(start -0.12065 -0.2794)
			(end -0.12065 -0.3048)
			(stroke
				(width 0.1)
				(type default)
			)
			(layer "B.Fab")
		)
		(fp_line
			(start -0.120396 0.2794)
			(end 0.12065 0.2794)
			(stroke
				(width 0.1)
				(type default)
			)
			(layer "B.Fab")
		)
		(fp_line
			(start -0.120396 0.3048)
			(end -0.120396 0.2794)
			(stroke
				(width 0.1)
				(type default)
			)
			(layer "B.Fab")
		)
		(fp_line
			(start 0.12065 -0.305054)
			(end 0.12065 -0.2794)
			(stroke
				(width 0.1)
				(type default)
			)
			(layer "B.Fab")
		)
		(fp_line
			(start 0.12065 -0.2794)
			(end -0.12065 -0.2794)
			(stroke
				(width 0.1)
				(type default)
			)
			(layer "B.Fab")
		)
		(fp_line
			(start 0.12065 0.2794)
			(end 0.12065 0.3048)
			(stroke
				(width 0.1)
				(type default)
			)
			(layer "B.Fab")
		)
		(fp_line
			(start 0.12065 0.3048)
			(end 0.67945 0.3048)
			(stroke
				(width 0.1)
				(type default)
			)
			(layer "B.Fab")
		)
		(fp_line
			(start 0.67945 -0.305054)
			(end 0.12065 -0.305054)
			(stroke
				(width 0.1)
				(type default)
			)
			(layer "B.Fab")
		)
		(fp_line
			(start 0.67945 0.3048)
			(end 0.67945 -0.305054)
			(stroke
				(width 0.1)
				(type default)
			)
			(layer "B.Fab")
		)
		(pad "1" smd circle
			(at 0.40005 0 180)
			(size 0 0)
			(layers "B.Cu" "B.Mask" "B.Paste")
			(net "P3V3_AUX")
		)
		(pad "2" smd circle
			(at -0.40005 0 180)
			(size 0 0)
			(layers "B.Cu" "B.Mask" "B.Paste")
			(net "SMB_FAN_3V3AUX_BUF_SCL")
		)
	)
	(footprint ""
		(layer "B.Cu")
		(at 330.17206 -32.700468 -90)
		(property "Reference" "R374"
			(at 0 0 90)
			(layer "B.SilkS")
			(hide yes)
			(effects
				(font
					(size 1.27 1.27)
				)
				(justify mirror)
			)
		)
		(property "Value" ""
			(at 0 0 90)
			(layer "B.Fab")
			(effects
				(font
					(size 1.27 1.27)
				)
				(justify mirror)
			)
		)
		(duplicate_pad_numbers_are_jumpers no)
		(fp_line
			(start -0.7874 0.4064)
			(end 0.7874 0.4064)
			(stroke
				(width 0.1524)
				(type default)
			)
			(layer "B.SilkS")
		)
		(fp_line
			(start 0.7874 0.4064)
			(end 0.7874 -0.4064)
			(stroke
				(width 0.1524)
				(type default)
			)
			(layer "B.SilkS")
		)
		(fp_line
			(start -0.7874 -0.4064)
			(end -0.7874 0.4064)
			(stroke
				(width 0.1524)
				(type default)
			)
			(layer "B.SilkS")
		)
		(fp_line
			(start 0.7874 -0.4064)
			(end -0.7874 -0.4064)
			(stroke
				(width 0.1524)
				(type default)
			)
			(layer "B.SilkS")
		)
		(fp_line
			(start -0.67945 0.3048)
			(end -0.120396 0.3048)
			(stroke
				(width 0.1)
				(type default)
			)
			(layer "B.Fab")
		)
		(fp_line
			(start -0.120396 0.3048)
			(end -0.120396 0.2794)
			(stroke
				(width 0.1)
				(type default)
			)
			(layer "B.Fab")
		)
		(fp_line
			(start 0.12065 0.3048)
			(end 0.67945 0.3048)
			(stroke
				(width 0.1)
				(type default)
			)
			(layer "B.Fab")
		)
		(fp_line
			(start 0.67945 0.3048)
			(end 0.67945 -0.305054)
			(stroke
				(width 0.1)
				(type default)
			)
			(layer "B.Fab")
		)
		(fp_line
			(start -0.120396 0.2794)
			(end 0.12065 0.2794)
			(stroke
				(width 0.1)
				(type default)
			)
			(layer "B.Fab")
		)
		(fp_line
			(start 0.12065 0.2794)
			(end 0.12065 0.3048)
			(stroke
				(width 0.1)
				(type default)
			)
			(layer "B.Fab")
		)
		(fp_line
			(start -0.12065 -0.2794)
			(end -0.12065 -0.3048)
			(stroke
				(width 0.1)
				(type default)
			)
			(layer "B.Fab")
		)
		(fp_line
			(start 0.12065 -0.2794)
			(end -0.12065 -0.2794)
			(stroke
				(width 0.1)
				(type default)
			)
			(layer "B.Fab")
		)
		(fp_line
			(start -0.67945 -0.3048)
			(end -0.67945 0.3048)
			(stroke
				(width 0.1)
				(type default)
			)
			(layer "B.Fab")
		)
		(fp_line
			(start -0.12065 -0.3048)
			(end -0.67945 -0.3048)
			(stroke
				(width 0.1)
				(type default)
			)
			(layer "B.Fab")
		)
		(fp_line
			(start 0.12065 -0.305054)
			(end 0.12065 -0.2794)
			(stroke
				(width 0.1)
				(type default)
			)
			(layer "B.Fab")
		)
		(fp_line
			(start 0.67945 -0.305054)
			(end 0.12065 -0.305054)
			(stroke
				(width 0.1)
				(type default)
			)
			(layer "B.Fab")
		)
		(pad "1" smd circle
			(at 0.40005 0 90)
			(size 0 0)
			(layers "B.Cu" "B.Mask" "B.Paste")
			(net "P3V3_AUX")
		)
		(pad "2" smd circle
			(at -0.40005 0 90)
			(size 0 0)
			(layers "B.Cu" "B.Mask" "B.Paste")
			(net "FM_SPI_3V3_1V8_VOLTAGE")
		)
	)
)
